# T6G (Grand Teton) — schematic netlist excerpt (pin names and nets, part order shuffled) for the footprints in the layout excerpt that follows; sources: Cadence DE-HDL packaged netlist, KiCad conversion of 04192023_DAF0TMB3IC0_F0TG_MB_C_brd_V02_OCP.brd

R6188  Q_RES  4.7K 5% EMPTY  pkg 0402LF  page 83 : A = FM_SEC_MUX_SEL ; B = P3V3_AUX
C1568  Q_CAP_DIFFBUS  DIFF BUS_0.22UF 6.3V 20% X6S  pkg C0201  page 65 : \1\ = P5E_CPU0_G3_TX_C_DN<5> ; \2\ = P5E_CPU0_G3_TX_DN<5>
C927  Q_CAP_DIFFBUS  DIFF BUS_0.22UF 6.3V 20% X6S  pkg C0201  page 63 : \1\ = P5E_CPU0_P0_TX_C_DP<3> ; \2\ = P5E_CPU0_P0_TX_DP<3>

(kicad_pcb
	(version 20260206)
	(generator "pcbnew")
	(generator_version "10.0")
	(general
		(thickness 1.6)
		(legacy_teardrops no)
	)
	(paper "A4")
	(title_block
		(title "04192023_DAF0TMB3IC0_F0TG_MB_C_brd_V02_OCP.brd")
		(comment 1 "Grand Teton / footprints 4848-4850 of 8354")
	)
	(layers
		(0 "F.Cu" signal "TOP")
		(4 "In1.Cu" signal "GND")
		(6 "In2.Cu" signal "IN1")
		(8 "In3.Cu" signal "GND1")
		(10 "In4.Cu" signal "IN2")
		(12 "In5.Cu" signal "GND2")
		(14 "In6.Cu" signal "IN3")
		(16 "In7.Cu" signal "GND3")
		(18 "In8.Cu" signal "VCC")
		(20 "In9.Cu" signal "VCC1")
		(22 "In10.Cu" signal "GND4")
		(24 "In11.Cu" signal "IN4")
		(26 "In12.Cu" signal "GND5")
		(28 "In13.Cu" signal "IN5")
		(30 "In14.Cu" signal "GND6")
		(32 "In15.Cu" signal "IN6")
		(34 "In16.Cu" signal "GND7")
		(2 "B.Cu" signal "BOTTOM")
		(9 "F.Adhes" user "F.Adhesive")
		(11 "B.Adhes" user "B.Adhesive")
		(13 "F.Paste" user "Package Geometry/Pastemask Top")
		(15 "B.Paste" user "Package Geometry/Pastemask Bottom")
		(5 "F.SilkS" user "Ref Des/Silkscreen Top")
		(7 "B.SilkS" user "Ref Des/Silkscreen Bottom")
		(1 "F.Mask" user "Board Geometry/Soldermask Top")
		(3 "B.Mask" user "Board Geometry/Soldermask Bottom")
		(17 "Dwgs.User" user "User.Drawings")
		(19 "Cmts.User" user "User.Comments")
		(21 "Eco1.User" user "User.Eco1")
		(23 "Eco2.User" user "User.Eco2")
		(25 "Edge.Cuts" user "Board Geometry/Outline")
		(27 "Margin" user)
		(31 "F.CrtYd" user "Package Geometry/Place Bound Top")
		(29 "B.CrtYd" user "Package Geometry/Place Bound Bottom")
		(35 "F.Fab" user "Ref Des/Assembly Top")
		(33 "B.Fab" user "Ref Des/Assembly Bottom")
	)
	(footprint ""
		(layer "F.Cu")
		(at 163.59632 -102.00132 180)
		(property "Reference" "R6188"
			(at 0 0 180)
			(layer "F.SilkS")
			(hide yes)
			(effects
				(font
					(size 1.27 1.27)
				)
			)
		)
		(property "Value" ""
			(at 0 0 180)
			(layer "F.Fab")
			(effects
				(font
					(size 1.27 1.27)
				)
			)
		)
		(duplicate_pad_numbers_are_jumpers no)
		(fp_line
			(start 0.7874 0.4064)
			(end -0.7874 0.4064)
			(stroke
				(width 0.1524)
				(type default)
			)
			(layer "F.SilkS")
		)
		(fp_line
			(start 0.7874 -0.4064)
			(end 0.7874 0.4064)
			(stroke
				(width 0.1524)
				(type default)
			)
			(layer "F.SilkS")
		)
		(fp_line
			(start -0.7874 0.4064)
			(end -0.7874 -0.4064)
			(stroke
				(width 0.1524)
				(type default)
			)
			(layer "F.SilkS")
		)
		(fp_line
			(start -0.7874 -0.4064)
			(end 0.7874 -0.4064)
			(stroke
				(width 0.1524)
				(type default)
			)
			(layer "F.SilkS")
		)
		(fp_line
			(start 0.67945 0.3048)
			(end 0.120396 0.3048)
			(stroke
				(width 0.1)
				(type default)
			)
			(layer "F.Fab")
		)
		(fp_line
			(start 0.67945 -0.3048)
			(end 0.67945 0.3048)
			(stroke
				(width 0.1)
				(type default)
			)
			(layer "F.Fab")
		)
		(fp_line
			(start 0.12065 -0.2794)
			(end 0.12065 -0.3048)
			(stroke
				(width 0.1)
				(type default)
			)
			(layer "F.Fab")
		)
		(fp_line
			(start 0.12065 -0.3048)
			(end 0.67945 -0.3048)
			(stroke
				(width 0.1)
				(type default)
			)
			(layer "F.Fab")
		)
		(fp_line
			(start 0.120396 0.3048)
			(end 0.120396 0.2794)
			(stroke
				(width 0.1)
				(type default)
			)
			(layer "F.Fab")
		)
		(fp_line
			(start 0.120396 0.2794)
			(end -0.12065 0.2794)
			(stroke
				(width 0.1)
				(type default)
			)
			(layer "F.Fab")
		)
		(fp_line
			(start -0.12065 0.3048)
			(end -0.67945 0.3048)
			(stroke
				(width 0.1)
				(type default)
			)
			(layer "F.Fab")
		)
		(fp_line
			(start -0.12065 0.2794)
			(end -0.12065 0.3048)
			(stroke
				(width 0.1)
				(type default)
			)
			(layer "F.Fab")
		)
		(fp_line
			(start -0.12065 -0.2794)
			(end 0.12065 -0.2794)
			(stroke
				(width 0.1)
				(type default)
			)
			(layer "F.Fab")
		)
		(fp_line
			(start -0.12065 -0.305054)
			(end -0.12065 -0.2794)
			(stroke
				(width 0.1)
				(type default)
			)
			(layer "F.Fab")
		)
		(fp_line
			(start -0.67945 0.3048)
			(end -0.67945 -0.305054)
			(stroke
				(width 0.1)
				(type default)
			)
			(layer "F.Fab")
		)
		(fp_line
			(start -0.67945 -0.305054)
			(end -0.12065 -0.305054)
			(stroke
				(width 0.1)
				(type default)
			)
			(layer "F.Fab")
		)
		(pad "1" smd circle
			(at -0.40005 0 180)
			(size 0 0)
			(layers "F.Cu" "F.Mask" "F.Paste")
			(net "FM_SEC_MUX_SEL")
		)
		(pad "2" smd circle
			(at 0.40005 0 180)
			(size 0 0)
			(layers "F.Cu" "F.Mask" "F.Paste")
			(net "P3V3_AUX")
		)
	)
	(footprint ""
		(layer "F.Cu")
		(at 300.691296 -378.95403 -90)
		(property "Reference" "C927"
			(at 0 0 270)
			(layer "F.SilkS")
			(hide yes)
			(effects
				(font
					(size 1.27 1.27)
				)
			)
		)
		(property "Value" ""
			(at 0 0 270)
			(layer "F.Fab")
			(effects
				(font
					(size 1.27 1.27)
				)
			)
		)
		(duplicate_pad_numbers_are_jumpers no)
		(fp_line
			(start -0.299974 0.150114)
			(end -0.299974 -0.150114)
			(stroke
				(width 0.1)
				(type default)
			)
			(layer "F.Fab")
		)
		(fp_line
			(start 0.299974 0.150114)
			(end -0.299974 0.150114)
			(stroke
				(width 0.1)
				(type default)
			)
			(layer "F.Fab")
		)
		(fp_line
			(start -0.299974 -0.150114)
			(end 0.299974 -0.150114)
			(stroke
				(width 0.1)
				(type default)
			)
			(layer "F.Fab")
		)
		(fp_line
			(start 0.299974 -0.150114)
			(end 0.299974 0.150114)
			(stroke
				(width 0.1)
				(type default)
			)
			(layer "F.Fab")
		)
		(pad "1" smd rect
			(at -0.2667 0 270)
			(size 0.3048 0.381)
			(layers "F.Cu" "F.Mask" "F.Paste")
			(net "P5E_CPU0_P0_TX_C_DP<3>")
		)
		(pad "2" smd rect
			(at 0.2667 0 270)
			(size 0.3048 0.381)
			(layers "F.Cu" "F.Mask" "F.Paste")
			(net "P5E_CPU0_P0_TX_DP<3>")
		)
	)
	(footprint ""
		(layer "F.Cu")
		(at 418.253164 -16.100298 90)
		(property "Reference" "C1568"
			(at 0 0 90)
			(layer "F.SilkS")
			(hide yes)
			(effects
				(font
					(size 1.27 1.27)
				)
			)
		)
		(property "Value" ""
			(at 0 0 90)
			(layer "F.Fab")
			(effects
				(font
					(size 1.27 1.27)
				)
			)
		)
		(duplicate_pad_numbers_are_jumpers no)
		(fp_line
			(start 0.299974 -0.150114)
			(end 0.299974 0.150114)
			(stroke
				(width 0.1)
				(type default)
			)
			(layer "F.Fab")
		)
		(fp_line
			(start -0.299974 -0.150114)
			(end 0.299974 -0.150114)
			(stroke
				(width 0.1)
				(type default)
			)
			(layer "F.Fab")
		)
		(fp_line
			(start 0.299974 0.150114)
			(end -0.299974 0.150114)
			(stroke
				(width 0.1)
				(type default)
			)
			(layer "F.Fab")
		)
		(fp_line
			(start -0.299974 0.150114)
			(end -0.299974 -0.150114)
			(stroke
				(width 0.1)
				(type default)
			)
			(layer "F.Fab")
		)
		(pad "1" smd rect
			(at -0.2667 0 90)
			(size 0.3048 0.381)
			(layers "F.Cu" "F.Mask" "F.Paste")
			(net "P5E_CPU0_G3_TX_C_DN<5>")
		)
		(pad "2" smd rect
			(at 0.2667 0 90)
			(size 0.3048 0.381)
			(layers "F.Cu" "F.Mask" "F.Paste")
			(net "P5E_CPU0_G3_TX_DN<5>")
		)
	)
)
